(kicad_pcb
	(version 20260206)
	(generator "pcbnew")
	(generator_version "10.0")
	(general
		(thickness 1.6)
		(legacy_teardrops no)
	)
	(paper "A4")
	(title_block
		(title "03242023_DA0F0TMBIJ0_F0T_Motherboard_J_brd_V01_OCP.brd")
		(comment 1 "Grand Teton / footprints 1400-1405 of 6105")
	)
	(layers
		(0 "F.Cu" signal "TOP")
		(4 "In1.Cu" signal "GND")
		(6 "In2.Cu" signal "IN1")
		(8 "In3.Cu" signal "GND1")
		(10 "In4.Cu" signal "IN2")
		(12 "In5.Cu" signal "GND2")
		(14 "In6.Cu" signal "IN3")
		(16 "In7.Cu" signal "GND3")
		(18 "In8.Cu" signal "VCC")
		(20 "In9.Cu" signal "VCC1")
		(22 "In10.Cu" signal "GND4")
		(24 "In11.Cu" signal "IN4")
		(26 "In12.Cu" signal "GND5")
		(28 "In13.Cu" signal "IN5")
		(30 "In14.Cu" signal "GND6")
		(32 "In15.Cu" signal "IN6")
		(34 "In16.Cu" signal "GND7")
		(2 "B.Cu" signal "BOTTOM")
		(9 "F.Adhes" user "F.Adhesive")
		(11 "B.Adhes" user "B.Adhesive")
		(13 "F.Paste" user "Package Geometry/Pastemask Top")
		(15 "B.Paste" user "Package Geometry/Pastemask Bottom")
		(5 "F.SilkS" user "Ref Des/Silkscreen Top")
		(7 "B.SilkS" user "Ref Des/Silkscreen Bottom")
		(1 "F.Mask" user "Board Geometry/Soldermask Top")
		(3 "B.Mask" user "Board Geometry/Soldermask Bottom")
		(17 "Dwgs.User" user "User.Drawings")
		(19 "Cmts.User" user "User.Comments")
		(21 "Eco1.User" user "User.Eco1")
		(23 "Eco2.User" user "User.Eco2")
		(25 "Edge.Cuts" user "Board Geometry/Outline")
		(27 "Margin" user)
		(31 "F.CrtYd" user "Package Geometry/Place Bound Top")
		(29 "B.CrtYd" user "Package Geometry/Place Bound Bottom")
		(35 "F.Fab" user "Ref Des/Assembly Top")
		(33 "B.Fab" user "Ref Des/Assembly Bottom")
	)
	(footprint ""
		(layer "F.Cu")
		(at 200.035414 -78.42377 180)
		(property "Reference" "R1293"
			(at 0 0 180)
			(layer "F.SilkS")
			(hide yes)
			(effects
				(font
					(size 1.27 1.27)
				)
			)
		)
		(property "Value" ""
			(at 0 0 180)
			(layer "F.Fab")
			(effects
				(font
					(size 1.27 1.27)
				)
			)
		)
		(duplicate_pad_numbers_are_jumpers no)
		(fp_line
			(start 0.7874 0.4064)
			(end -0.7874 0.4064)
			(stroke
				(width 0.1524)
				(type default)
			)
			(layer "F.SilkS")
		)
		(fp_line
			(start 0.7874 -0.4064)
			(end 0.7874 0.4064)
			(stroke
				(width 0.1524)
				(type default)
			)
			(layer "F.SilkS")
		)
		(fp_line
			(start -0.7874 0.4064)
			(end -0.7874 -0.4064)
			(stroke
				(width 0.1524)
				(type default)
			)
			(layer "F.SilkS")
		)
		(fp_line
			(start -0.7874 -0.4064)
			(end 0.7874 -0.4064)
			(stroke
				(width 0.1524)
				(type default)
			)
			(layer "F.SilkS")
		)
		(fp_line
			(start 0.67945 0.3048)
			(end 0.120396 0.3048)
			(stroke
				(width 0.1)
				(type default)
			)
			(layer "F.Fab")
		)
		(fp_line
			(start 0.67945 -0.3048)
			(end 0.67945 0.3048)
			(stroke
				(width 0.1)
				(type default)
			)
			(layer "F.Fab")
		)
		(fp_line
			(start 0.12065 -0.2794)
			(end 0.12065 -0.3048)
			(stroke
				(width 0.1)
				(type default)
			)
			(layer "F.Fab")
		)
		(fp_line
			(start 0.12065 -0.3048)
			(end 0.67945 -0.3048)
			(stroke
				(width 0.1)
				(type default)
			)
			(layer "F.Fab")
		)
		(fp_line
			(start 0.120396 0.3048)
			(end 0.120396 0.2794)
			(stroke
				(width 0.1)
				(type default)
			)
			(layer "F.Fab")
		)
		(fp_line
			(start 0.120396 0.2794)
			(end -0.12065 0.2794)
			(stroke
				(width 0.1)
				(type default)
			)
			(layer "F.Fab")
		)
		(fp_line
			(start -0.12065 0.3048)
			(end -0.67945 0.3048)
			(stroke
				(width 0.1)
				(type default)
			)
			(layer "F.Fab")
		)
		(fp_line
			(start -0.12065 0.2794)
			(end -0.12065 0.3048)
			(stroke
				(width 0.1)
				(type default)
			)
			(layer "F.Fab")
		)
		(fp_line
			(start -0.12065 -0.2794)
			(end 0.12065 -0.2794)
			(stroke
				(width 0.1)
				(type default)
			)
			(layer "F.Fab")
		)
		(fp_line
			(start -0.12065 -0.305054)
			(end -0.12065 -0.2794)
			(stroke
				(width 0.1)
				(type default)
			)
			(layer "F.Fab")
		)
		(fp_line
			(start -0.67945 0.3048)
			(end -0.67945 -0.305054)
			(stroke
				(width 0.1)
				(type default)
			)
			(layer "F.Fab")
		)
		(fp_line
			(start -0.67945 -0.305054)
			(end -0.12065 -0.305054)
			(stroke
				(width 0.1)
				(type default)
			)
			(layer "F.Fab")
		)
		(pad "1" smd circle
			(at -0.40005 0 180)
			(size 0 0)
			(layers "F.Cu" "F.Mask" "F.Paste")
			(net "NCSI_BMC_RXD1_R")
		)
		(pad "2" smd circle
			(at 0.40005 0 180)
			(size 0 0)
			(layers "F.Cu" "F.Mask" "F.Paste")
			(net "RMII_OCP_BMC_RXD_1")
		)
	)
	(footprint ""
		(layer "F.Cu")
		(at 20.785582 -423.629836 -90)
		(property "Reference" "R3516"
			(at 0 0 270)
			(layer "F.SilkS")
			(hide yes)
			(effects
				(font
					(size 1.27 1.27)
				)
			)
		)
		(property "Value" ""
			(at 0 0 270)
			(layer "F.Fab")
			(effects
				(font
					(size 1.27 1.27)
				)
			)
		)
		(duplicate_pad_numbers_are_jumpers no)
		(fp_line
			(start -0.7874 0.4064)
			(end -0.7874 -0.4064)
			(stroke
				(width 0.1524)
				(type default)
			)
			(layer "F.SilkS")
		)
		(fp_line
			(start 0.7874 0.4064)
			(end -0.7874 0.4064)
			(stroke
				(width 0.1524)
				(type default)
			)
			(layer "F.SilkS")
		)
		(fp_line
			(start -0.7874 -0.4064)
			(end 0.7874 -0.4064)
			(stroke
				(width 0.1524)
				(type default)
			)
			(layer "F.SilkS")
		)
		(fp_line
			(start 0.7874 -0.4064)
			(end 0.7874 0.4064)
			(stroke
				(width 0.1524)
				(type default)
			)
			(layer "F.SilkS")
		)
		(fp_line
			(start -0.67945 0.3048)
			(end -0.67945 -0.305054)
			(stroke
				(width 0.1)
				(type default)
			)
			(layer "F.Fab")
		)
		(fp_line
			(start -0.12065 0.3048)
			(end -0.67945 0.3048)
			(stroke
				(width 0.1)
				(type default)
			)
			(layer "F.Fab")
		)
		(fp_line
			(start 0.120396 0.3048)
			(end 0.120396 0.2794)
			(stroke
				(width 0.1)
				(type default)
			)
			(layer "F.Fab")
		)
		(fp_line
			(start 0.67945 0.3048)
			(end 0.120396 0.3048)
			(stroke
				(width 0.1)
				(type default)
			)
			(layer "F.Fab")
		)
		(fp_line
			(start -0.12065 0.2794)
			(end -0.12065 0.3048)
			(stroke
				(width 0.1)
				(type default)
			)
			(layer "F.Fab")
		)
		(fp_line
			(start 0.120396 0.2794)
			(end -0.12065 0.2794)
			(stroke
				(width 0.1)
				(type default)
			)
			(layer "F.Fab")
		)
		(fp_line
			(start -0.12065 -0.2794)
			(end 0.12065 -0.2794)
			(stroke
				(width 0.1)
				(type default)
			)
			(layer "F.Fab")
		)
		(fp_line
			(start 0.12065 -0.2794)
			(end 0.12065 -0.3048)
			(stroke
				(width 0.1)
				(type default)
			)
			(layer "F.Fab")
		)
		(fp_line
			(start 0.12065 -0.3048)
			(end 0.67945 -0.3048)
			(stroke
				(width 0.1)
				(type default)
			)
			(layer "F.Fab")
		)
		(fp_line
			(start 0.67945 -0.3048)
			(end 0.67945 0.3048)
			(stroke
				(width 0.1)
				(type default)
			)
			(layer "F.Fab")
		)
		(fp_line
			(start -0.67945 -0.305054)
			(end -0.12065 -0.305054)
			(stroke
				(width 0.1)
				(type default)
			)
			(layer "F.Fab")
		)
		(fp_line
			(start -0.12065 -0.305054)
			(end -0.12065 -0.2794)
			(stroke
				(width 0.1)
				(type default)
			)
			(layer "F.Fab")
		)
		(pad "1" smd circle
			(at -0.40005 0 270)
			(size 0 0)
			(layers "F.Cu" "F.Mask" "F.Paste")
			(net "GPU_BASE_ID0")
		)
		(pad "2" smd circle
			(at 0.40005 0 270)
			(size 0 0)
			(layers "F.Cu" "F.Mask" "F.Paste")
			(net "GPU_BASE_ID0_R")
		)
	)
	(footprint ""
		(layer "F.Cu")
		(at 49.139094 -169.708322 90)
		(property "Reference" "PC374"
			(at 0 0 90)
			(layer "F.SilkS")
			(hide yes)
			(effects
				(font
					(size 1.27 1.27)
				)
			)
		)
		(property "Value" ""
			(at 0 0 90)
			(layer "F.Fab")
			(effects
				(font
					(size 1.27 1.27)
				)
			)
		)
		(duplicate_pad_numbers_are_jumpers no)
		(fp_line
			(start 0.7874 -0.4064)
			(end 0.7874 0.4064)
			(stroke
				(width 0.1524)
				(type default)
			)
			(layer "F.SilkS")
		)
		(fp_line
			(start -0.7874 -0.4064)
			(end 0.7874 -0.4064)
			(stroke
				(width 0.1524)
				(type default)
			)
			(layer "F.SilkS")
		)
		(fp_line
			(start 0.7874 0.4064)
			(end -0.7874 0.4064)
			(stroke
				(width 0.1524)
				(type default)
			)
			(layer "F.SilkS")
		)
		(fp_line
			(start -0.7874 0.4064)
			(end -0.7874 -0.4064)
			(stroke
				(width 0.1524)
				(type default)
			)
			(layer "F.SilkS")
		)
		(fp_line
			(start -0.12065 -0.305054)
			(end -0.12065 -0.2794)
			(stroke
				(width 0.1)
				(type default)
			)
			(layer "F.Fab")
		)
		(fp_line
			(start -0.67945 -0.305054)
			(end -0.12065 -0.305054)
			(stroke
				(width 0.1)
				(type default)
			)
			(layer "F.Fab")
		)
		(fp_line
			(start 0.67945 -0.3048)
			(end 0.67945 0.3048)
			(stroke
				(width 0.1)
				(type default)
			)
			(layer "F.Fab")
		)
		(fp_line
			(start 0.12065 -0.3048)
			(end 0.67945 -0.3048)
			(stroke
				(width 0.1)
				(type default)
			)
			(layer "F.Fab")
		)
		(fp_line
			(start 0.12065 -0.2794)
			(end 0.12065 -0.3048)
			(stroke
				(width 0.1)
				(type default)
			)
			(layer "F.Fab")
		)
		(fp_line
			(start -0.12065 -0.2794)
			(end 0.12065 -0.2794)
			(stroke
				(width 0.1)
				(type default)
			)
			(layer "F.Fab")
		)
		(fp_line
			(start 0.120396 0.2794)
			(end -0.12065 0.2794)
			(stroke
				(width 0.1)
				(type default)
			)
			(layer "F.Fab")
		)
		(fp_line
			(start -0.12065 0.2794)
			(end -0.12065 0.3048)
			(stroke
				(width 0.1)
				(type default)
			)
			(layer "F.Fab")
		)
		(fp_line
			(start 0.67945 0.3048)
			(end 0.120396 0.3048)
			(stroke
				(width 0.1)
				(type default)
			)
			(layer "F.Fab")
		)
		(fp_line
			(start 0.120396 0.3048)
			(end 0.120396 0.2794)
			(stroke
				(width 0.1)
				(type default)
			)
			(layer "F.Fab")
		)
		(fp_line
			(start -0.12065 0.3048)
			(end -0.67945 0.3048)
			(stroke
				(width 0.1)
				(type default)
			)
			(layer "F.Fab")
		)
		(fp_line
			(start -0.67945 0.3048)
			(end -0.67945 -0.305054)
			(stroke
				(width 0.1)
				(type default)
			)
			(layer "F.Fab")
		)
		(pad "1" smd circle
			(at -0.40005 0 90)
			(size 0 0)
			(layers "F.Cu" "F.Mask" "F.Paste")
			(net "SW_P12V_PVCCINFAON_CPU1_FLT")
		)
		(pad "2" smd circle
			(at 0.40005 0 90)
			(size 0 0)
			(layers "F.Cu" "F.Mask" "F.Paste")
			(net "GND")
		)
	)
	(footprint ""
		(layer "F.Cu")
		(at 418.919914 -139.88669 90)
		(property "Reference" "PR435"
			(at 0 0 90)
			(layer "F.SilkS")
			(hide yes)
			(effects
				(font
					(size 1.27 1.27)
				)
			)
		)
		(property "Value" ""
			(at 0 0 90)
			(layer "F.Fab")
			(effects
				(font
					(size 1.27 1.27)
				)
			)
		)
		(duplicate_pad_numbers_are_jumpers no)
		(fp_line
			(start 0.7874 -0.4064)
			(end 0.7874 0.4064)
			(stroke
				(width 0.1524)
				(type default)
			)
			(layer "F.SilkS")
		)
		(fp_line
			(start -0.7874 -0.4064)
			(end 0.7874 -0.4064)
			(stroke
				(width 0.1524)
				(type default)
			)
			(layer "F.SilkS")
		)
		(fp_line
			(start 0.7874 0.4064)
			(end -0.7874 0.4064)
			(stroke
				(width 0.1524)
				(type default)
			)
			(layer "F.SilkS")
		)
		(fp_line
			(start -0.7874 0.4064)
			(end -0.7874 -0.4064)
			(stroke
				(width 0.1524)
				(type default)
			)
			(layer "F.SilkS")
		)
		(fp_line
			(start -0.12065 -0.305054)
			(end -0.12065 -0.2794)
			(stroke
				(width 0.1)
				(type default)
			)
			(layer "F.Fab")
		)
		(fp_line
			(start -0.67945 -0.305054)
			(end -0.12065 -0.305054)
			(stroke
				(width 0.1)
				(type default)
			)
			(layer "F.Fab")
		)
		(fp_line
			(start 0.67945 -0.3048)
			(end 0.67945 0.3048)
			(stroke
				(width 0.1)
				(type default)
			)
			(layer "F.Fab")
		)
		(fp_line
			(start 0.12065 -0.3048)
			(end 0.67945 -0.3048)
			(stroke
				(width 0.1)
				(type default)
			)
			(layer "F.Fab")
		)
		(fp_line
			(start 0.12065 -0.2794)
			(end 0.12065 -0.3048)
			(stroke
				(width 0.1)
				(type default)
			)
			(layer "F.Fab")
		)
		(fp_line
			(start -0.12065 -0.2794)
			(end 0.12065 -0.2794)
			(stroke
				(width 0.1)
				(type default)
			)
			(layer "F.Fab")
		)
		(fp_line
			(start 0.120396 0.2794)
			(end -0.12065 0.2794)
			(stroke
				(width 0.1)
				(type default)
			)
			(layer "F.Fab")
		)
		(fp_line
			(start -0.12065 0.2794)
			(end -0.12065 0.3048)
			(stroke
				(width 0.1)
				(type default)
			)
			(layer "F.Fab")
		)
		(fp_line
			(start 0.67945 0.3048)
			(end 0.120396 0.3048)
			(stroke
				(width 0.1)
				(type default)
			)
			(layer "F.Fab")
		)
		(fp_line
			(start 0.120396 0.3048)
			(end 0.120396 0.2794)
			(stroke
				(width 0.1)
				(type default)
			)
			(layer "F.Fab")
		)
		(fp_line
			(start -0.12065 0.3048)
			(end -0.67945 0.3048)
			(stroke
				(width 0.1)
				(type default)
			)
			(layer "F.Fab")
		)
		(fp_line
			(start -0.67945 0.3048)
			(end -0.67945 -0.305054)
			(stroke
				(width 0.1)
				(type default)
			)
			(layer "F.Fab")
		)
		(pad "1" smd circle
			(at -0.40005 0 90)
			(size 0 0)
			(layers "F.Cu" "F.Mask" "F.Paste")
			(net "PVCCINFAON_CPU0_ATSEN")
		)
		(pad "2" smd circle
			(at 0.40005 0 90)
			(size 0 0)
			(layers "F.Cu" "F.Mask" "F.Paste")
			(net "GND")
		)
	)
	(footprint ""
		(layer "F.Cu")
		(at 209.74558 -132.862828)
		(property "Reference" "R1690"
			(at 0 0 0)
			(layer "F.SilkS")
			(hide yes)
			(effects
				(font
					(size 1.27 1.27)
				)
			)
		)
		(property "Value" ""
			(at 0 0 0)
			(layer "F.Fab")
			(effects
				(font
					(size 1.27 1.27)
				)
			)
		)
		(duplicate_pad_numbers_are_jumpers no)
		(fp_line
			(start -0.7874 -0.4064)
			(end 0.7874 -0.4064)
			(stroke
				(width 0.1524)
				(type default)
			)
			(layer "F.SilkS")
		)
		(fp_line
			(start -0.7874 0.4064)
			(end -0.7874 -0.4064)
			(stroke
				(width 0.1524)
				(type default)
			)
			(layer "F.SilkS")
		)
		(fp_line
			(start 0.7874 -0.4064)
			(end 0.7874 0.4064)
			(stroke
				(width 0.1524)
				(type default)
			)
			(layer "F.SilkS")
		)
		(fp_line
			(start 0.7874 0.4064)
			(end -0.7874 0.4064)
			(stroke
				(width 0.1524)
				(type default)
			)
			(layer "F.SilkS")
		)
		(fp_line
			(start -0.67945 -0.305054)
			(end -0.12065 -0.305054)
			(stroke
				(width 0.1)
				(type default)
			)
			(layer "F.Fab")
		)
		(fp_line
			(start -0.67945 0.3048)
			(end -0.67945 -0.305054)
			(stroke
				(width 0.1)
				(type default)
			)
			(layer "F.Fab")
		)
		(fp_line
			(start -0.12065 -0.305054)
			(end -0.12065 -0.2794)
			(stroke
				(width 0.1)
				(type default)
			)
			(layer "F.Fab")
		)
		(fp_line
			(start -0.12065 -0.2794)
			(end 0.12065 -0.2794)
			(stroke
				(width 0.1)
				(type default)
			)
			(layer "F.Fab")
		)
		(fp_line
			(start -0.12065 0.2794)
			(end -0.12065 0.3048)
			(stroke
				(width 0.1)
				(type default)
			)
			(layer "F.Fab")
		)
		(fp_line
			(start -0.12065 0.3048)
			(end -0.67945 0.3048)
			(stroke
				(width 0.1)
				(type default)
			)
			(layer "F.Fab")
		)
		(fp_line
			(start 0.120396 0.2794)
			(end -0.12065 0.2794)
			(stroke
				(width 0.1)
				(type default)
			)
			(layer "F.Fab")
		)
		(fp_line
			(start 0.120396 0.3048)
			(end 0.120396 0.2794)
			(stroke
				(width 0.1)
				(type default)
			)
			(layer "F.Fab")
		)
		(fp_line
			(start 0.12065 -0.3048)
			(end 0.67945 -0.3048)
			(stroke
				(width 0.1)
				(type default)
			)
			(layer "F.Fab")
		)
		(fp_line
			(start 0.12065 -0.2794)
			(end 0.12065 -0.3048)
			(stroke
				(width 0.1)
				(type default)
			)
			(layer "F.Fab")
		)
		(fp_line
			(start 0.67945 -0.3048)
			(end 0.67945 0.3048)
			(stroke
				(width 0.1)
				(type default)
			)
			(layer "F.Fab")
		)
		(fp_line
			(start 0.67945 0.3048)
			(end 0.120396 0.3048)
			(stroke
				(width 0.1)
				(type default)
			)
			(layer "F.Fab")
		)
		(pad "1" smd circle
			(at -0.40005 0)
			(size 0 0)
			(layers "F.Cu" "F.Mask" "F.Paste")
			(net "P3V3_AUX")
		)
		(pad "2" smd circle
			(at 0.40005 0)
			(size 0 0)
			(layers "F.Cu" "F.Mask" "F.Paste")
			(net "FM_COMP_P3V3_AUX_ENIN")
		)
	)
	(footprint ""
		(layer "F.Cu")
		(at 52.480972 -436.376318)
		(property "Reference" "R2898"
			(at 0 0 0)
			(layer "F.SilkS")
			(hide yes)
			(effects
				(font
					(size 1.27 1.27)
				)
			)
		)
		(property "Value" ""
			(at 0 0 0)
			(layer "F.Fab")
			(effects
				(font
					(size 1.27 1.27)
				)
			)
		)
		(duplicate_pad_numbers_are_jumpers no)
		(fp_line
			(start -0.7874 -0.4064)
			(end 0.7874 -0.4064)
			(stroke
				(width 0.1524)
				(type default)
			)
			(layer "F.SilkS")
		)
		(fp_line
			(start -0.7874 0.4064)
			(end -0.7874 -0.4064)
			(stroke
				(width 0.1524)
				(type default)
			)
			(layer "F.SilkS")
		)
		(fp_line
			(start 0.7874 -0.4064)
			(end 0.7874 0.4064)
			(stroke
				(width 0.1524)
				(type default)
			)
			(layer "F.SilkS")
		)
		(fp_line
			(start 0.7874 0.4064)
			(end -0.7874 0.4064)
			(stroke
				(width 0.1524)
				(type default)
			)
			(layer "F.SilkS")
		)
		(fp_line
			(start -0.67945 -0.305054)
			(end -0.12065 -0.305054)
			(stroke
				(width 0.1)
				(type default)
			)
			(layer "F.Fab")
		)
		(fp_line
			(start -0.67945 0.3048)
			(end -0.67945 -0.305054)
			(stroke
				(width 0.1)
				(type default)
			)
			(layer "F.Fab")
		)
		(fp_line
			(start -0.12065 -0.305054)
			(end -0.12065 -0.2794)
			(stroke
				(width 0.1)
				(type default)
			)
			(layer "F.Fab")
		)
		(fp_line
			(start -0.12065 -0.2794)
			(end 0.12065 -0.2794)
			(stroke
				(width 0.1)
				(type default)
			)
			(layer "F.Fab")
		)
		(fp_line
			(start -0.12065 0.2794)
			(end -0.12065 0.3048)
			(stroke
				(width 0.1)
				(type default)
			)
			(layer "F.Fab")
		)
		(fp_line
			(start -0.12065 0.3048)
			(end -0.67945 0.3048)
			(stroke
				(width 0.1)
				(type default)
			)
			(layer "F.Fab")
		)
		(fp_line
			(start 0.120396 0.2794)
			(end -0.12065 0.2794)
			(stroke
				(width 0.1)
				(type default)
			)
			(layer "F.Fab")
		)
		(fp_line
			(start 0.120396 0.3048)
			(end 0.120396 0.2794)
			(stroke
				(width 0.1)
				(type default)
			)
			(layer "F.Fab")
		)
		(fp_line
			(start 0.12065 -0.3048)
			(end 0.67945 -0.3048)
			(stroke
				(width 0.1)
				(type default)
			)
			(layer "F.Fab")
		)
		(fp_line
			(start 0.12065 -0.2794)
			(end 0.12065 -0.3048)
			(stroke
				(width 0.1)
				(type default)
			)
			(layer "F.Fab")
		)
		(fp_line
			(start 0.67945 -0.3048)
			(end 0.67945 0.3048)
			(stroke
				(width 0.1)
				(type default)
			)
			(layer "F.Fab")
		)
		(fp_line
			(start 0.67945 0.3048)
			(end 0.120396 0.3048)
			(stroke
				(width 0.1)
				(type default)
			)
			(layer "F.Fab")
		)
		(pad "1" smd circle
			(at -0.40005 0)
			(size 0 0)
			(layers "F.Cu" "F.Mask" "F.Paste")
			(net "SMB_1_BMC_GPU_BUF_R_SDA")
		)
		(pad "2" smd circle
			(at 0.40005 0)
			(size 0 0)
			(layers "F.Cu" "F.Mask" "F.Paste")
			(net "SMB_1_BMC_GPU_BUF_SDA")
		)
	)
)
